# T6G (Grand Teton) — schematic netlist excerpt (pin names and nets, part order shuffled) for the footprints in the layout excerpt that follows; sources: Cadence DE-HDL packaged netlist, KiCad conversion of 04192023_DAF0TMB3IC0_F0TG_MB_C_brd_V02_OCP.brd

PU202  MAX15090BEWIT  MAX15090BEWI+T IC  pkg BGA28_0-5_3-525X2-065  page 134
  ISENSE  = P3V3_OCP_SENSE_1
  VCC  = P3V3_OCP_VCC_1
  IN_A3  = P3V3_AUX
  OUT_A4  = P3V3_OCP_SFF_R
  IN_A5  = P3V3_AUX
  GATE  = P3V3_OCP_GATE_PU202_1
  CDLY  = GND
  CB  = P3V3_OCP_CB_1
  GND_B2  = GND
  IN_B3  = P3V3_AUX
  OUT_B4  = P3V3_OCP_SFF_R
  IN_B5  = P3V3_AUX
  OUT_B6  = P3V3_OCP_SFF_R
  \en#\  = GND
  GND_C1  = GND
  GND_C2  = GND
  IN_C3  = P3V3_AUX
  OUT_C4  = P3V3_OCP_SFF_R
  IN_C5  = P3V3_AUX
  OUT_C6  = P3V3_OCP_SFF_R
  \fault#\  = P3V3_OCP_FAULT_1
  REG  = P3V3_OCP_REG_1
  UV  = P3V3_OCP_UV_1
  OV  = P3V3_OCP_OV_1
  OUT_D4  = P3V3_OCP_SFF_R
  IN_D5  = P3V3_AUX
  OUT_D6  = P3V3_OCP_SFF_R
  PG  = P3V3_OCP_PWRGD_1

(kicad_pcb
	(version 20260206)
	(generator "pcbnew")
	(generator_version "10.0")
	(general
		(thickness 1.6)
		(legacy_teardrops no)
	)
	(paper "A4")
	(title_block
		(title "04192023_DAF0TMB3IC0_F0TG_MB_C_brd_V02_OCP.brd")
		(comment 1 "Grand Teton / footprints 3020-3020 of 8354")
	)
	(layers
		(0 "F.Cu" signal "TOP")
		(4 "In1.Cu" signal "GND")
		(6 "In2.Cu" signal "IN1")
		(8 "In3.Cu" signal "GND1")
		(10 "In4.Cu" signal "IN2")
		(12 "In5.Cu" signal "GND2")
		(14 "In6.Cu" signal "IN3")
		(16 "In7.Cu" signal "GND3")
		(18 "In8.Cu" signal "VCC")
		(20 "In9.Cu" signal "VCC1")
		(22 "In10.Cu" signal "GND4")
		(24 "In11.Cu" signal "IN4")
		(26 "In12.Cu" signal "GND5")
		(28 "In13.Cu" signal "IN5")
		(30 "In14.Cu" signal "GND6")
		(32 "In15.Cu" signal "IN6")
		(34 "In16.Cu" signal "GND7")
		(2 "B.Cu" signal "BOTTOM")
		(9 "F.Adhes" user "F.Adhesive")
		(11 "B.Adhes" user "B.Adhesive")
		(13 "F.Paste" user "Package Geometry/Pastemask Top")
		(15 "B.Paste" user "Package Geometry/Pastemask Bottom")
		(5 "F.SilkS" user "Ref Des/Silkscreen Top")
		(7 "B.SilkS" user "Ref Des/Silkscreen Bottom")
		(1 "F.Mask" user "Board Geometry/Soldermask Top")
		(3 "B.Mask" user "Board Geometry/Soldermask Bottom")
		(17 "Dwgs.User" user "User.Drawings")
		(19 "Cmts.User" user "User.Comments")
		(21 "Eco1.User" user "User.Eco1")
		(23 "Eco2.User" user "User.Eco2")
		(25 "Edge.Cuts" user "Board Geometry/Outline")
		(27 "Margin" user)
		(31 "F.CrtYd" user "Package Geometry/Place Bound Top")
		(29 "B.CrtYd" user "Package Geometry/Place Bound Bottom")
		(35 "F.Fab" user "Ref Des/Assembly Top")
		(33 "B.Fab" user "Ref Des/Assembly Bottom")
	)
	(footprint ""
		(layer "F.Cu")
		(at 431.828956 -105.32745 -90)
		(property "Reference" "PU202"
			(at 1.905 3.718306 90)
			(unlocked yes)
			(layer "F.SilkS")
			(effects
				(font
					(size 0.7874 0.5842)
					(thickness 0.1524)
				)
				(justify left)
			)
		)
		(property "Value" ""
			(at 0 0 270)
			(layer "F.Fab")
			(effects
				(font
					(size 1.27 1.27)
				)
			)
		)
		(duplicate_pad_numbers_are_jumpers no)
		(fp_line
			(start -1.774952 1.039876)
			(end 1.774952 1.039876)
			(stroke
				(width 0.1524)
				(type default)
			)
			(layer "F.SilkS")
		)
		(fp_line
			(start 1.774952 1.039876)
			(end 1.774952 -1.039876)
			(stroke
				(width 0.1524)
				(type default)
			)
			(layer "F.SilkS")
		)
		(fp_line
			(start -1.774952 -1.039876)
			(end -1.774952 1.039876)
			(stroke
				(width 0.1524)
				(type default)
			)
			(layer "F.SilkS")
		)
		(fp_line
			(start 1.774952 -1.039876)
			(end -1.774952 -1.039876)
			(stroke
				(width 0.1524)
				(type default)
			)
			(layer "F.SilkS")
		)
		(fp_poly
			(pts
				(xy -0.999998 -1.801876) (xy -0.999998 -1.039876) (xy -1.769872 -1.039876) (xy -1.769872 -0.249936)
				(xy -2.531872 -0.249936) (xy -2.531872 -1.801876)
			)
			(stroke
				(width 0)
				(type default)
			)
			(fill yes)
			(layer "F.SilkS")
		)
		(fp_line
			(start -1.769872 1.039876)
			(end 1.769872 1.039876)
			(stroke
				(width 0.1)
				(type default)
			)
			(layer "F.Fab")
		)
		(fp_line
			(start 1.769872 1.039876)
			(end 1.769872 -1.039876)
			(stroke
				(width 0.1)
				(type default)
			)
			(layer "F.Fab")
		)
		(fp_line
			(start -1.769872 -1.039876)
			(end -1.769872 1.039876)
			(stroke
				(width 0.1)
				(type default)
			)
			(layer "F.Fab")
		)
		(fp_line
			(start 1.769872 -1.039876)
			(end -1.769872 -1.039876)
			(stroke
				(width 0.1)
				(type default)
			)
			(layer "F.Fab")
		)
		(fp_poly
			(pts
				(xy -1.769872 -1.039876) (xy -0.999998 -1.039876) (xy -0.999998 -1.801876) (xy -2.531872 -1.801876)
				(xy -2.531872 -0.249936) (xy -1.769872 -0.249936)
			)
			(stroke
				(width 0)
				(type default)
			)
			(fill yes)
			(layer "F.Fab")
		)
		(pad "A1" smd circle
			(at -1.500124 -0.750062 270)
			(size 0.2286 0.2286)
			(layers "F.Cu" "F.Mask" "F.Paste")
			(net "P3V3_OCP_SENSE_1")
		)
		(pad "A2" smd circle
			(at -0.999998 -0.750062 270)
			(size 0.2286 0.2286)
			(layers "F.Cu" "F.Mask" "F.Paste")
			(net "P3V3_OCP_VCC_1")
		)
		(pad "A3" smd circle
			(at -0.499872 -0.750062 270)
			(size 0.2286 0.2286)
			(layers "F.Cu" "F.Mask" "F.Paste")
			(net "P3V3_AUX")
		)
		(pad "A4" smd circle
			(at 0 -0.750062 270)
			(size 0.2286 0.2286)
			(layers "F.Cu" "F.Mask" "F.Paste")
			(net "P3V3_OCP_SFF_R")
		)
		(pad "A5" smd circle
			(at 0.499872 -0.750062 270)
			(size 0.2286 0.2286)
			(layers "F.Cu" "F.Mask" "F.Paste")
			(net "P3V3_AUX")
		)
		(pad "A6" smd circle
			(at 0.999998 -0.750062 270)
			(size 0.2286 0.2286)
			(layers "F.Cu" "F.Mask" "F.Paste")
			(net "P3V3_OCP_GATE_PU202_1")
		)
		(pad "A7" smd circle
			(at 1.500124 -0.750062 270)
			(size 0.2286 0.2286)
			(layers "F.Cu" "F.Mask" "F.Paste")
			(net "GND")
		)
		(pad "B1" smd circle
			(at -1.500124 -0.249936 270)
			(size 0.2286 0.2286)
			(layers "F.Cu" "F.Mask" "F.Paste")
			(net "P3V3_OCP_CB_1")
		)
		(pad "B2" smd circle
			(at -0.999998 -0.249936 270)
			(size 0.2286 0.2286)
			(layers "F.Cu" "F.Mask" "F.Paste")
			(net "GND")
		)
		(pad "B3" smd circle
			(at -0.499872 -0.249936 270)
			(size 0.2286 0.2286)
			(layers "F.Cu" "F.Mask" "F.Paste")
			(net "P3V3_AUX")
		)
		(pad "B4" smd circle
			(at 0 -0.249936 270)
			(size 0.2286 0.2286)
			(layers "F.Cu" "F.Mask" "F.Paste")
			(net "P3V3_OCP_SFF_R")
		)
		(pad "B5" smd circle
			(at 0.499872 -0.249936 270)
			(size 0.2286 0.2286)
			(layers "F.Cu" "F.Mask" "F.Paste")
			(net "P3V3_AUX")
		)
		(pad "B6" smd circle
			(at 0.999998 -0.249936 270)
			(size 0.2286 0.2286)
			(layers "F.Cu" "F.Mask" "F.Paste")
			(net "P3V3_OCP_SFF_R")
		)
		(pad "B7" smd circle
			(at 1.500124 -0.249936 270)
			(size 0.2286 0.2286)
			(layers "F.Cu" "F.Mask" "F.Paste")
			(net "GND")
		)
		(pad "C1" smd circle
			(at -1.500124 0.249936 270)
			(size 0.2286 0.2286)
			(layers "F.Cu" "F.Mask" "F.Paste")
			(net "GND")
		)
		(pad "C2" smd circle
			(at -0.999998 0.249936 270)
			(size 0.2286 0.2286)
			(layers "F.Cu" "F.Mask" "F.Paste")
			(net "GND")
		)
		(pad "C3" smd circle
			(at -0.499872 0.249936 270)
			(size 0.2286 0.2286)
			(layers "F.Cu" "F.Mask" "F.Paste")
			(net "P3V3_AUX")
		)
		(pad "C4" smd circle
			(at 0 0.249936 270)
			(size 0.2286 0.2286)
			(layers "F.Cu" "F.Mask" "F.Paste")
			(net "P3V3_OCP_SFF_R")
		)
		(pad "C5" smd circle
			(at 0.499872 0.249936 270)
			(size 0.2286 0.2286)
			(layers "F.Cu" "F.Mask" "F.Paste")
			(net "P3V3_AUX")
		)
		(pad "C6" smd circle
			(at 0.999998 0.249936 270)
			(size 0.2286 0.2286)
			(layers "F.Cu" "F.Mask" "F.Paste")
			(net "P3V3_OCP_SFF_R")
		)
		(pad "C7" smd circle
			(at 1.500124 0.249936 270)
			(size 0.2286 0.2286)
			(layers "F.Cu" "F.Mask" "F.Paste")
			(net "P3V3_OCP_FAULT_1")
		)
		(pad "D1" smd circle
			(at -1.500124 0.750062 270)
			(size 0.2286 0.2286)
			(layers "F.Cu" "F.Mask" "F.Paste")
			(net "P3V3_OCP_REG_1")
		)
		(pad "D2" smd circle
			(at -0.999998 0.750062 270)
			(size 0.2286 0.2286)
			(layers "F.Cu" "F.Mask" "F.Paste")
			(net "P3V3_OCP_UV_1")
		)
		(pad "D3" smd circle
			(at -0.499872 0.750062 270)
			(size 0.2286 0.2286)
			(layers "F.Cu" "F.Mask" "F.Paste")
			(net "P3V3_OCP_OV_1")
		)
		(pad "D4" smd circle
			(at 0 0.750062 270)
			(size 0.2286 0.2286)
			(layers "F.Cu" "F.Mask" "F.Paste")
			(net "P3V3_OCP_SFF_R")
		)
		(pad "D5" smd circle
			(at 0.499872 0.750062 270)
			(size 0.2286 0.2286)
			(layers "F.Cu" "F.Mask" "F.Paste")
			(net "P3V3_AUX")
		)
		(pad "D6" smd circle
			(at 0.999998 0.750062 270)
			(size 0.2286 0.2286)
			(layers "F.Cu" "F.Mask" "F.Paste")
			(net "P3V3_OCP_SFF_R")
		)
		(pad "D7" smd circle
			(at 1.500124 0.750062 270)
			(size 0.2286 0.2286)
			(layers "F.Cu" "F.Mask" "F.Paste")
			(net "P3V3_OCP_PWRGD_1")
		)
	)
)
